(kicad_pcb
	(version 20260206)
	(generator "pcbnew")
	(generator_version "10.0")
	(general
		(thickness 1.6)
		(legacy_teardrops no)
	)
	(paper "A4")
	(title_block
		(title "Wiwynn_Tioga_Pass_MB.brd")
		(comment 1 "Tioga Pass / footprints 4525-4532 of 4770")
	)
	(layers
		(0 "F.Cu" signal "TOP")
		(4 "In1.Cu" signal "L2GND")
		(6 "In2.Cu" signal "L3")
		(8 "In3.Cu" signal "L4GND")
		(10 "In4.Cu" signal "L5")
		(12 "In5.Cu" signal "L6GND")
		(14 "In6.Cu" signal "L7VCC")
		(16 "In7.Cu" signal "L8VCC")
		(18 "In8.Cu" signal "L9GND")
		(20 "In9.Cu" signal "L10")
		(22 "In10.Cu" signal "L11GND")
		(24 "In11.Cu" signal "L12")
		(26 "In12.Cu" signal "L13GND")
		(2 "B.Cu" signal "BOTTOM")
		(9 "F.Adhes" user "F.Adhesive")
		(11 "B.Adhes" user "B.Adhesive")
		(13 "F.Paste" user "Package Geometry/Pastemask Top")
		(15 "B.Paste" user "Package Geometry/Pastemask Bottom")
		(5 "F.SilkS" user "Ref Des/Silkscreen Top")
		(7 "B.SilkS" user "Ref Des/Silkscreen Bottom")
		(1 "F.Mask" user "Board Geometry/Soldermask Top")
		(3 "B.Mask" user "Board Geometry/Soldermask Bottom")
		(17 "Dwgs.User" user "User.Drawings")
		(19 "Cmts.User" user "User.Comments")
		(21 "Eco1.User" user "User.Eco1")
		(23 "Eco2.User" user "User.Eco2")
		(25 "Edge.Cuts" user "Board Geometry/Outline")
		(27 "Margin" user)
		(31 "F.CrtYd" user "Package Geometry/Place Bound Top")
		(29 "B.CrtYd" user "Package Geometry/Place Bound Bottom")
		(35 "F.Fab" user "Ref Des/Assembly Top")
		(33 "B.Fab" user "Ref Des/Assembly Bottom")
	)
	(footprint ""
		(layer "B.Cu")
		(at 86.436708 -125.99162 90)
		(property "Reference" "R7L2"
			(at 0 0 90)
			(layer "B.SilkS")
			(hide yes)
			(effects
				(font
					(size 1.27 1.27)
				)
				(justify mirror)
			)
		)
		(property "Value" ""
			(at 0 0 90)
			(layer "B.Fab")
			(effects
				(font
					(size 1.27 1.27)
				)
				(justify mirror)
			)
		)
		(duplicate_pad_numbers_are_jumpers no)
		(fp_poly
			(pts
				(xy 0.2794 -0.1016) (xy -0.2794 -0.1016) (xy -0.2794 0.9906) (xy 0.2794 0.9906)
			)
			(stroke
				(width 0)
				(type default)
			)
			(fill no)
			(layer "B.CrtYd")
		)
		(fp_line
			(start 0.2794 -0.1016)
			(end 0.2794 0.9906)
			(stroke
				(width 0.1)
				(type default)
			)
			(layer "B.Fab")
		)
		(fp_line
			(start -0.2794 -0.1016)
			(end 0.2794 -0.1016)
			(stroke
				(width 0.1)
				(type default)
			)
			(layer "B.Fab")
		)
		(fp_line
			(start 0.2794 0.9906)
			(end -0.2794 0.9906)
			(stroke
				(width 0.1)
				(type default)
			)
			(layer "B.Fab")
		)
		(fp_line
			(start -0.2794 0.9906)
			(end -0.2794 -0.1016)
			(stroke
				(width 0.1)
				(type default)
			)
			(layer "B.Fab")
		)
		(pad "1" smd rect
			(at 0 0 270)
			(size 0.508 0.508)
			(layers "B.Cu" "B.Mask" "B.Paste")
			(net "VSENSE_PVDDQ_KLM_P")
		)
		(pad "2" smd rect
			(at 0 0.889 270)
			(size 0.508 0.508)
			(layers "B.Cu" "B.Mask" "B.Paste")
			(net "VSENSE_PVDDQ_KLM_N")
		)
		(zone
			(layer "B.Cu")
			(hatch none 0.5)
			(connect_pads
				(clearance 0)
			)
			(min_thickness 0.25)
			(keepout
				(tracks allowed)
				(vias not_allowed)
				(pads allowed)
				(copperpour not_allowed)
				(footprints allowed)
			)
			(placement
				(enabled no)
				(sheetname "")
			)
			(fill
				(thermal_gap 0.5)
				(thermal_bridge_width 0.5)
				(island_removal_mode 0)
			)
			(polygon
				(pts
					(xy 86.690708 -126.24562) (xy 86.690708 -125.73762) (xy 87.071708 -125.73762) (xy 87.071708 -126.24562)
				)
			)
		)
		(zone
			(layer "B.Cu")
			(hatch none 0.5)
			(connect_pads
				(clearance 0)
			)
			(min_thickness 0.25)
			(keepout
				(tracks not_allowed)
				(vias allowed)
				(pads allowed)
				(copperpour not_allowed)
				(footprints allowed)
			)
			(placement
				(enabled no)
				(sheetname "")
			)
			(fill
				(thermal_gap 0.5)
				(thermal_bridge_width 0.5)
				(island_removal_mode 0)
			)
			(polygon
				(pts
					(xy 87.071708 -126.24562) (xy 87.071708 -125.73762) (xy 86.690708 -125.73762) (xy 86.690708 -126.24562)
				)
			)
		)
	)
	(footprint ""
		(layer "B.Cu")
		(at 395.478 -29.845 -90)
		(property "Reference" "R2T22"
			(at 0 0 90)
			(layer "B.SilkS")
			(hide yes)
			(effects
				(font
					(size 1.27 1.27)
				)
				(justify mirror)
			)
		)
		(property "Value" ""
			(at 0 0 90)
			(layer "B.Fab")
			(effects
				(font
					(size 1.27 1.27)
				)
				(justify mirror)
			)
		)
		(duplicate_pad_numbers_are_jumpers no)
		(fp_poly
			(pts
				(xy 0.2794 -0.1016) (xy -0.2794 -0.1016) (xy -0.2794 0.9906) (xy 0.2794 0.9906)
			)
			(stroke
				(width 0)
				(type default)
			)
			(fill no)
			(layer "B.CrtYd")
		)
		(fp_line
			(start -0.2794 0.9906)
			(end -0.2794 -0.1016)
			(stroke
				(width 0.1)
				(type default)
			)
			(layer "B.Fab")
		)
		(fp_line
			(start 0.2794 0.9906)
			(end -0.2794 0.9906)
			(stroke
				(width 0.1)
				(type default)
			)
			(layer "B.Fab")
		)
		(fp_line
			(start -0.2794 -0.1016)
			(end 0.2794 -0.1016)
			(stroke
				(width 0.1)
				(type default)
			)
			(layer "B.Fab")
		)
		(fp_line
			(start 0.2794 -0.1016)
			(end 0.2794 0.9906)
			(stroke
				(width 0.1)
				(type default)
			)
			(layer "B.Fab")
		)
		(pad "1" smd rect
			(at 0 0 90)
			(size 0.508 0.508)
			(layers "B.Cu" "B.Mask" "B.Paste")
			(net "P3V3_STBY")
		)
		(pad "2" smd rect
			(at 0 0.889 90)
			(size 0.508 0.508)
			(layers "B.Cu" "B.Mask" "B.Paste")
			(net "RST_BMC_SYSRST_BTN_OUT_B_R_N")
		)
	)
	(footprint ""
		(layer "B.Cu")
		(at 295.8846 -68.154804)
		(property "Reference" "R4P18"
			(at 0 0 0)
			(layer "B.SilkS")
			(hide yes)
			(effects
				(font
					(size 1.27 1.27)
				)
				(justify mirror)
			)
		)
		(property "Value" ""
			(at 0 0 0)
			(layer "B.Fab")
			(effects
				(font
					(size 1.27 1.27)
				)
				(justify mirror)
			)
		)
		(duplicate_pad_numbers_are_jumpers no)
		(fp_poly
			(pts
				(xy 0.2794 -0.1016) (xy -0.2794 -0.1016) (xy -0.2794 0.9906) (xy 0.2794 0.9906)
			)
			(stroke
				(width 0)
				(type default)
			)
			(fill no)
			(layer "B.CrtYd")
		)
		(fp_line
			(start -0.2794 -0.1016)
			(end 0.2794 -0.1016)
			(stroke
				(width 0.1)
				(type default)
			)
			(layer "B.Fab")
		)
		(fp_line
			(start -0.2794 0.9906)
			(end -0.2794 -0.1016)
			(stroke
				(width 0.1)
				(type default)
			)
			(layer "B.Fab")
		)
		(fp_line
			(start 0.2794 -0.1016)
			(end 0.2794 0.9906)
			(stroke
				(width 0.1)
				(type default)
			)
			(layer "B.Fab")
		)
		(fp_line
			(start 0.2794 0.9906)
			(end -0.2794 0.9906)
			(stroke
				(width 0.1)
				(type default)
			)
			(layer "B.Fab")
		)
		(pad "1" smd rect
			(at 0 0 180)
			(size 0.508 0.508)
			(layers "B.Cu" "B.Mask" "B.Paste")
			(net "H_PM_SYNC_GTL_R1")
		)
		(pad "2" smd rect
			(at 0 0.889 180)
			(size 0.508 0.508)
			(layers "B.Cu" "B.Mask" "B.Paste")
			(net "H_PM_SYNC_GTL")
		)
		(zone
			(layer "B.Cu")
			(hatch none 0.5)
			(connect_pads
				(clearance 0)
			)
			(min_thickness 0.25)
			(keepout
				(tracks allowed)
				(vias not_allowed)
				(pads allowed)
				(copperpour not_allowed)
				(footprints allowed)
			)
			(placement
				(enabled no)
				(sheetname "")
			)
			(fill
				(thermal_gap 0.5)
				(thermal_bridge_width 0.5)
				(island_removal_mode 0)
			)
			(polygon
				(pts
					(xy 296.1386 -67.900804) (xy 295.6306 -67.900804) (xy 295.6306 -67.519804) (xy 296.1386 -67.519804)
				)
			)
		)
		(zone
			(layer "B.Cu")
			(hatch none 0.5)
			(connect_pads
				(clearance 0)
			)
			(min_thickness 0.25)
			(keepout
				(tracks not_allowed)
				(vias allowed)
				(pads allowed)
				(copperpour not_allowed)
				(footprints allowed)
			)
			(placement
				(enabled no)
				(sheetname "")
			)
			(fill
				(thermal_gap 0.5)
				(thermal_bridge_width 0.5)
				(island_removal_mode 0)
			)
			(polygon
				(pts
					(xy 296.1386 -67.519804) (xy 295.6306 -67.519804) (xy 295.6306 -67.900804) (xy 296.1386 -67.900804)
				)
			)
		)
	)
	(footprint ""
		(layer "B.Cu")
		(at 479.9711 -39.5224 90)
		(property "Reference" "C1R19"
			(at 0 0 90)
			(layer "B.SilkS")
			(hide yes)
			(effects
				(font
					(size 1.27 1.27)
				)
				(justify mirror)
			)
		)
		(property "Value" ""
			(at 0 0 90)
			(layer "B.Fab")
			(effects
				(font
					(size 1.27 1.27)
				)
				(justify mirror)
			)
		)
		(duplicate_pad_numbers_are_jumpers no)
		(fp_poly
			(pts
				(xy -0.3048 -0.1016) (xy -0.3048 0.9906) (xy 0.3048 0.9906) (xy 0.3048 -0.1016)
			)
			(stroke
				(width 0)
				(type default)
			)
			(fill no)
			(layer "B.CrtYd")
		)
		(fp_line
			(start 0.3048 -0.1016)
			(end 0.3048 0.9906)
			(stroke
				(width 0.1)
				(type default)
			)
			(layer "B.Fab")
		)
		(fp_line
			(start -0.3048 -0.1016)
			(end 0.3048 -0.1016)
			(stroke
				(width 0.1)
				(type default)
			)
			(layer "B.Fab")
		)
		(fp_line
			(start 0.3048 0.9906)
			(end -0.3048 0.9906)
			(stroke
				(width 0.1)
				(type default)
			)
			(layer "B.Fab")
		)
		(fp_line
			(start -0.3048 0.9906)
			(end -0.3048 -0.1016)
			(stroke
				(width 0.1)
				(type default)
			)
			(layer "B.Fab")
		)
		(pad "1" smd rect
			(at 0 0 270)
			(size 0.508 0.508)
			(layers "B.Cu" "B.Mask" "B.Paste")
			(net "P1V5_LAN")
		)
		(pad "2" smd rect
			(at 0 0.889 270)
			(size 0.508 0.508)
			(layers "B.Cu" "B.Mask" "B.Paste")
			(net "GND")
		)
		(zone
			(layer "B.Cu")
			(hatch none 0.5)
			(connect_pads
				(clearance 0)
			)
			(min_thickness 0.25)
			(keepout
				(tracks allowed)
				(vias not_allowed)
				(pads allowed)
				(copperpour not_allowed)
				(footprints allowed)
			)
			(placement
				(enabled no)
				(sheetname "")
			)
			(fill
				(thermal_gap 0.5)
				(thermal_bridge_width 0.5)
				(island_removal_mode 0)
			)
			(polygon
				(pts
					(xy 480.2251 -39.7764) (xy 480.2251 -39.2684) (xy 480.6061 -39.2684) (xy 480.6061 -39.7764)
				)
			)
		)
		(zone
			(layer "B.Cu")
			(hatch none 0.5)
			(connect_pads
				(clearance 0)
			)
			(min_thickness 0.25)
			(keepout
				(tracks not_allowed)
				(vias allowed)
				(pads allowed)
				(copperpour not_allowed)
				(footprints allowed)
			)
			(placement
				(enabled no)
				(sheetname "")
			)
			(fill
				(thermal_gap 0.5)
				(thermal_bridge_width 0.5)
				(island_removal_mode 0)
			)
			(polygon
				(pts
					(xy 480.6061 -39.7764) (xy 480.6061 -39.2684) (xy 480.2251 -39.2684) (xy 480.2251 -39.7764)
				)
			)
		)
	)
	(footprint ""
		(layer "B.Cu")
		(at 260.377686 -77.82814)
		(property "Reference" "C5P26"
			(at 0 0 0)
			(layer "B.SilkS")
			(hide yes)
			(effects
				(font
					(size 1.27 1.27)
				)
				(justify mirror)
			)
		)
		(property "Value" ""
			(at 0 0 0)
			(layer "B.Fab")
			(effects
				(font
					(size 1.27 1.27)
				)
				(justify mirror)
			)
		)
		(duplicate_pad_numbers_are_jumpers no)
		(fp_poly
			(pts
				(xy 0.7239 -0.2159) (xy -0.7239 -0.2159) (xy -0.7239 1.9939) (xy 0.7239 1.9939)
			)
			(stroke
				(width 0)
				(type default)
			)
			(fill no)
			(layer "B.CrtYd")
		)
		(fp_line
			(start -0.7239 -0.2159)
			(end 0.7239 -0.2159)
			(stroke
				(width 0.1)
				(type default)
			)
			(layer "B.Fab")
		)
		(fp_line
			(start -0.7239 1.9939)
			(end -0.7239 -0.2159)
			(stroke
				(width 0.1)
				(type default)
			)
			(layer "B.Fab")
		)
		(fp_line
			(start 0.7239 -0.2159)
			(end 0.7239 1.9939)
			(stroke
				(width 0.1)
				(type default)
			)
			(layer "B.Fab")
		)
		(fp_line
			(start 0.7239 1.9939)
			(end -0.7239 1.9939)
			(stroke
				(width 0.1)
				(type default)
			)
			(layer "B.Fab")
		)
		(pad "1" smd rect
			(at 0 0 180)
			(size 1.27 1.016)
			(layers "B.Cu" "B.Mask" "B.Paste")
			(net "PVCCIN_CPU0")
		)
		(pad "2" smd rect
			(at 0 1.778 180)
			(size 1.27 1.016)
			(layers "B.Cu" "B.Mask" "B.Paste")
			(net "GND")
		)
		(zone
			(layer "B.Cu")
			(hatch none 0.5)
			(connect_pads
				(clearance 0)
			)
			(min_thickness 0.25)
			(keepout
				(tracks not_allowed)
				(vias allowed)
				(pads allowed)
				(copperpour not_allowed)
				(footprints allowed)
			)
			(placement
				(enabled no)
				(sheetname "")
			)
			(fill
				(thermal_gap 0.5)
				(thermal_bridge_width 0.5)
				(island_removal_mode 0)
			)
			(polygon
				(pts
					(xy 261.012686 -77.32014) (xy 259.742686 -77.32014) (xy 259.742686 -76.55814) (xy 261.012686 -76.55814)
				)
			)
		)
	)
	(footprint ""
		(layer "B.Cu")
		(at 248.8565 -140.208 -90)
		(property "Reference" "C5G65"
			(at -1.14681 0.76708 0)
			(unlocked yes)
			(layer "B.SilkS")
			(effects
				(font
					(size 0.7874 0.5842)
					(thickness 0.1524)
				)
				(justify mirror)
			)
		)
		(property "Value" ""
			(at 0 0 90)
			(layer "B.Fab")
			(effects
				(font
					(size 1.27 1.27)
				)
				(justify mirror)
			)
		)
		(duplicate_pad_numbers_are_jumpers no)
		(fp_rect
			(start 0.4953 1.6002)
			(end -0.4953 -0.2032)
			(stroke
				(width 0)
				(type default)
			)
			(fill no)
			(layer "B.CrtYd")
		)
		(fp_line
			(start -0.4953 1.6002)
			(end 0.4953 1.6002)
			(stroke
				(width 0.1)
				(type default)
			)
			(layer "B.Fab")
		)
		(fp_line
			(start 0.4953 1.6002)
			(end 0.4953 -0.2032)
			(stroke
				(width 0.1)
				(type default)
			)
			(layer "B.Fab")
		)
		(fp_line
			(start -0.4953 -0.2032)
			(end -0.4953 1.6002)
			(stroke
				(width 0.1)
				(type default)
			)
			(layer "B.Fab")
		)
		(fp_line
			(start 0.4953 -0.2032)
			(end -0.4953 -0.2032)
			(stroke
				(width 0.1)
				(type default)
			)
			(layer "B.Fab")
		)
		(pad "1" smd rect
			(at 0 0 90)
			(size 0.762 0.889)
			(layers "B.Cu" "B.Mask" "B.Paste")
			(net "PVDDQ_DEF")
		)
		(pad "2" smd rect
			(at 0 1.397 90)
			(size 0.762 0.889)
			(layers "B.Cu" "B.Mask" "B.Paste")
			(net "GND")
		)
		(zone
			(layer "B.Cu")
			(hatch none 0.5)
			(connect_pads
				(clearance 0)
			)
			(min_thickness 0.25)
			(keepout
				(tracks not_allowed)
				(vias allowed)
				(pads allowed)
				(copperpour not_allowed)
				(footprints allowed)
			)
			(placement
				(enabled no)
				(sheetname "")
			)
			(fill
				(thermal_gap 0.5)
				(thermal_bridge_width 0.5)
				(island_removal_mode 0)
			)
			(polygon
				(pts
					(xy 247.904 -139.827) (xy 248.412 -139.827) (xy 248.412 -140.589) (xy 247.904 -140.589)
				)
			)
		)
	)
	(footprint ""
		(layer "B.Cu")
		(at 477.84766 -27.70632 180)
		(property "Reference" "R2T25"
			(at 0 0 0)
			(layer "B.SilkS")
			(hide yes)
			(effects
				(font
					(size 1.27 1.27)
				)
				(justify mirror)
			)
		)
		(property "Value" ""
			(at 0 0 0)
			(layer "B.Fab")
			(effects
				(font
					(size 1.27 1.27)
				)
				(justify mirror)
			)
		)
		(duplicate_pad_numbers_are_jumpers no)
		(fp_poly
			(pts
				(xy 0.2794 -0.1016) (xy -0.2794 -0.1016) (xy -0.2794 0.9906) (xy 0.2794 0.9906)
			)
			(stroke
				(width 0)
				(type default)
			)
			(fill no)
			(layer "B.CrtYd")
		)
		(fp_line
			(start 0.2794 0.9906)
			(end -0.2794 0.9906)
			(stroke
				(width 0.1)
				(type default)
			)
			(layer "B.Fab")
		)
		(fp_line
			(start 0.2794 -0.1016)
			(end 0.2794 0.9906)
			(stroke
				(width 0.1)
				(type default)
			)
			(layer "B.Fab")
		)
		(fp_line
			(start -0.2794 0.9906)
			(end -0.2794 -0.1016)
			(stroke
				(width 0.1)
				(type default)
			)
			(layer "B.Fab")
		)
		(fp_line
			(start -0.2794 -0.1016)
			(end 0.2794 -0.1016)
			(stroke
				(width 0.1)
				(type default)
			)
			(layer "B.Fab")
		)
		(pad "1" smd rect
			(at 0 0)
			(size 0.508 0.508)
			(layers "B.Cu" "B.Mask" "B.Paste")
			(net "PD_CKMNG_OE")
		)
		(pad "2" smd rect
			(at 0 0.889)
			(size 0.508 0.508)
			(layers "B.Cu" "B.Mask" "B.Paste")
			(net "GND")
		)
		(zone
			(layer "B.Cu")
			(hatch none 0.5)
			(connect_pads
				(clearance 0)
			)
			(min_thickness 0.25)
			(keepout
				(tracks not_allowed)
				(vias allowed)
				(pads allowed)
				(copperpour not_allowed)
				(footprints allowed)
			)
			(placement
				(enabled no)
				(sheetname "")
			)
			(fill
				(thermal_gap 0.5)
				(thermal_bridge_width 0.5)
				(island_removal_mode 0)
			)
			(polygon
				(pts
					(xy 477.59366 -28.34132) (xy 478.10166 -28.34132) (xy 478.10166 -27.96032) (xy 477.59366 -27.96032)
				)
			)
		)
		(zone
			(layer "B.Cu")
			(hatch none 0.5)
			(connect_pads
				(clearance 0)
			)
			(min_thickness 0.25)
			(keepout
				(tracks allowed)
				(vias not_allowed)
				(pads allowed)
				(copperpour not_allowed)
				(footprints allowed)
			)
			(placement
				(enabled no)
				(sheetname "")
			)
			(fill
				(thermal_gap 0.5)
				(thermal_bridge_width 0.5)
				(island_removal_mode 0)
			)
			(polygon
				(pts
					(xy 477.59366 -27.96032) (xy 478.10166 -27.96032) (xy 478.10166 -28.34132) (xy 477.59366 -28.34132)
				)
			)
		)
	)
	(footprint ""
		(layer "B.Cu")
		(at 414.743646 -35.658552)
		(property "Reference" "C25W30"
			(at -0.97536 0.76708 90)
			(unlocked yes)
			(layer "B.SilkS")
			(effects
				(font
					(size 0.4064 0.254)
					(thickness 0.1524)
				)
				(justify mirror)
			)
		)
		(property "Value" ""
			(at 0 0 0)
			(layer "B.Fab")
			(effects
				(font
					(size 1.27 1.27)
				)
				(justify mirror)
			)
		)
		(duplicate_pad_numbers_are_jumpers no)
		(fp_poly
			(pts
				(xy 0.4953 -0.2032) (xy -0.4953 -0.2032) (xy -0.4953 1.6002) (xy 0.4953 1.6002)
			)
			(stroke
				(width 0)
				(type default)
			)
			(fill no)
			(layer "B.CrtYd")
		)
		(fp_line
			(start -0.4953 -0.2032)
			(end -0.4953 1.6002)
			(stroke
				(width 0.1)
				(type default)
			)
			(layer "B.Fab")
		)
		(fp_line
			(start -0.4953 1.6002)
			(end 0.4953 1.6002)
			(stroke
				(width 0.1)
				(type default)
			)
			(layer "B.Fab")
		)
		(fp_line
			(start 0.4953 -0.2032)
			(end -0.4953 -0.2032)
			(stroke
				(width 0.1)
				(type default)
			)
			(layer "B.Fab")
		)
		(fp_line
			(start 0.4953 1.6002)
			(end 0.4953 -0.2032)
			(stroke
				(width 0.1)
				(type default)
			)
			(layer "B.Fab")
		)
		(pad "1" smd rect
			(at 0 0 180)
			(size 0.762 0.889)
			(layers "B.Cu" "B.Mask" "B.Paste")
			(net "P1V15_AUX_BMC")
		)
		(pad "2" smd rect
			(at 0 1.397 180)
			(size 0.762 0.889)
			(layers "B.Cu" "B.Mask" "B.Paste")
			(net "GND")
		)
		(zone
			(layer "B.Cu")
			(hatch none 0.5)
			(connect_pads
				(clearance 0)
			)
			(min_thickness 0.25)
			(keepout
				(tracks not_allowed)
				(vias allowed)
				(pads allowed)
				(copperpour not_allowed)
				(footprints allowed)
			)
			(placement
				(enabled no)
				(sheetname "")
			)
			(fill
				(thermal_gap 0.5)
				(thermal_bridge_width 0.5)
				(island_removal_mode 0)
			)
			(polygon
				(pts
					(xy 415.124646 -35.214052) (xy 414.362646 -35.214052) (xy 414.362646 -34.706052) (xy 415.124646 -34.706052)
				)
			)
		)
	)
)
